(kicad_pcb
	(version 20260206)
	(generator "pcbnew")
	(generator_version "10.0")
	(general
		(thickness 1.6)
		(legacy_teardrops no)
	)
	(paper "A4")
	(title_block
		(title "panther-plus-userver — 13130-1b_20150205.brd")
		(comment 1 "Honey Badger (Wiwynn) / footprints 833-840 of 1509")
	)
	(layers
		(0 "F.Cu" signal "TOP")
		(4 "In1.Cu" signal "L2")
		(6 "In2.Cu" signal "L3")
		(8 "In3.Cu" signal "L4")
		(10 "In4.Cu" signal "L5")
		(12 "In5.Cu" signal "L6")
		(14 "In6.Cu" signal "L7")
		(16 "In7.Cu" signal "L8")
		(18 "In8.Cu" signal "L9")
		(20 "In9.Cu" signal "L10")
		(22 "In10.Cu" signal "L11")
		(2 "B.Cu" signal "BOTTOM")
		(9 "F.Adhes" user "F.Adhesive")
		(11 "B.Adhes" user "B.Adhesive")
		(13 "F.Paste" user "Package Geometry/Pastemask Top")
		(15 "B.Paste" user "Package Geometry/Pastemask Bottom")
		(5 "F.SilkS" user "Ref Des/Silkscreen Top")
		(7 "B.SilkS" user "Ref Des/Silkscreen Bottom")
		(1 "F.Mask" user "Board Geometry/Soldermask Top")
		(3 "B.Mask" user "Board Geometry/Soldermask Bottom")
		(17 "Dwgs.User" user "User.Drawings")
		(19 "Cmts.User" user "User.Comments")
		(21 "Eco1.User" user "User.Eco1")
		(23 "Eco2.User" user "User.Eco2")
		(25 "Edge.Cuts" user "Board Geometry/Outline")
		(27 "Margin" user)
		(31 "F.CrtYd" user "Package Geometry/Place Bound Top")
		(29 "B.CrtYd" user "Package Geometry/Place Bound Bottom")
		(35 "F.Fab" user "Ref Des/Assembly Top")
		(33 "B.Fab" user "Ref Des/Assembly Bottom")
	)
	(footprint ""
		(layer "B.Cu")
		(at 176.276 -42.291)
		(property "Reference" "C357"
			(at 0 0 0)
			(layer "B.SilkS")
			(hide yes)
			(effects
				(font
					(size 1.27 1.27)
				)
				(justify mirror)
			)
		)
		(property "Value" "SC1U6D3V3KX-2GP"
			(at 0.0254 -2.0193 0)
			(unlocked yes)
			(layer "B.Fab")
			(hide yes)
			(effects
				(font
					(size 1.016 1.016)
					(thickness 0.1524)
				)
				(justify mirror)
			)
		)
		(property "Device Type" "C603H36"
			(at 0.0254 -3.5433 0)
			(unlocked yes)
			(layer "B.Fab")
			(hide yes)
			(effects
				(font
					(size 1.016 1.016)
					(thickness 0.1524)
				)
				(justify mirror)
			)
		)
		(duplicate_pad_numbers_are_jumpers no)
		(fp_line
			(start 0.4064 0)
			(end -0.4064 0)
			(stroke
				(width 0.2286)
				(type default)
			)
			(layer "B.SilkS")
		)
		(fp_rect
			(start 0.635 1.1811)
			(end -0.635 -1.1811)
			(stroke
				(width 0)
				(type default)
			)
			(fill no)
			(layer "B.CrtYd")
		)
		(fp_rect
			(start 0.635 1.1811)
			(end -0.635 -1.1811)
			(stroke
				(width 0)
				(type default)
			)
			(fill no)
			(layer "B.Fab")
		)
		(pad "1" smd custom
			(at 0 -0.6604 180)
			(size 0.19685 0.19685)
			(layers "B.Cu" "B.Mask" "B.Paste")
			(net "SPI_SW_RST#")
			(options
				(clearance outline)
				(anchor circle)
			)
			(primitives
				(gr_poly
					(pts
						(arc
							(start 0.508 0.2921)
							(mid 0.478242 0.363942)
							(end 0.4064 0.3937)
						)
						(arc
							(start -0.4064 0.3937)
							(mid -0.478242 0.363942)
							(end -0.508 0.2921)
						)
						(arc
							(start -0.508 -0.2921)
							(mid -0.478242 -0.363942)
							(end -0.4064 -0.3937)
						)
						(arc
							(start 0.4064 -0.3937)
							(mid 0.478242 -0.363942)
							(end 0.508 -0.2921)
						)
					)
					(width 0)
					(fill yes)
				)
			)
		)
		(pad "2" smd custom
			(at 0 0.6604 180)
			(size 0.19685 0.19685)
			(layers "B.Cu" "B.Mask" "B.Paste")
			(net "GND")
			(options
				(clearance outline)
				(anchor circle)
			)
			(primitives
				(gr_poly
					(pts
						(arc
							(start 0.508 0.2921)
							(mid 0.478242 0.363942)
							(end 0.4064 0.3937)
						)
						(arc
							(start -0.4064 0.3937)
							(mid -0.478242 0.363942)
							(end -0.508 0.2921)
						)
						(arc
							(start -0.508 -0.2921)
							(mid -0.478242 -0.363942)
							(end -0.4064 -0.3937)
						)
						(arc
							(start 0.4064 -0.3937)
							(mid 0.478242 -0.363942)
							(end 0.508 -0.2921)
						)
					)
					(width 0)
					(fill yes)
				)
			)
		)
	)
	(footprint ""
		(layer "B.Cu")
		(at 97.917 -51.3588 180)
		(property "Reference" "C118"
			(at 0 0 0)
			(layer "B.SilkS")
			(hide yes)
			(effects
				(font
					(size 1.27 1.27)
				)
				(justify mirror)
			)
		)
		(property "Value" "SC1U10V2KX-1GP"
			(at -1.1811 -2.7051 180)
			(unlocked yes)
			(layer "B.Fab")
			(hide yes)
			(effects
				(font
					(size 1.016 1.016)
					(thickness 0.1524)
				)
				(justify mirror)
			)
		)
		(property "Device Type" "C402H22"
			(at -1.1811 -4.2291 180)
			(unlocked yes)
			(layer "B.Fab")
			(hide yes)
			(effects
				(font
					(size 1.016 1.016)
					(thickness 0.1524)
				)
				(justify mirror)
			)
		)
		(duplicate_pad_numbers_are_jumpers no)
		(fp_rect
			(start 0.381 0.7366)
			(end -0.381 -0.7366)
			(stroke
				(width 0)
				(type default)
			)
			(fill no)
			(layer "B.CrtYd")
		)
		(fp_rect
			(start 0.381 0.7366)
			(end -0.381 -0.7366)
			(stroke
				(width 0)
				(type default)
			)
			(fill no)
			(layer "B.Fab")
		)
		(pad "1" smd custom
			(at 0 -0.4572)
			(size 0.1143 0.1143)
			(layers "B.Cu" "B.Mask" "B.Paste")
			(net "VCCCLKDDR0")
			(options
				(clearance outline)
				(anchor circle)
			)
			(primitives
				(gr_poly
					(pts
						(arc
							(start -0.254 0.1778)
							(mid -0.239121 0.213721)
							(end -0.2032 0.2286)
						)
						(arc
							(start 0.2032 0.2286)
							(mid 0.239121 0.213721)
							(end 0.254 0.1778)
						)
						(arc
							(start 0.254 -0.1778)
							(mid 0.239121 -0.213721)
							(end 0.2032 -0.2286)
						)
						(arc
							(start -0.2032 -0.2286)
							(mid -0.239121 -0.213721)
							(end -0.254 -0.1778)
						)
					)
					(width 0)
					(fill yes)
				)
			)
		)
		(pad "2" smd custom
			(at 0 0.4572)
			(size 0.1143 0.1143)
			(layers "B.Cu" "B.Mask" "B.Paste")
			(net "GND")
			(options
				(clearance outline)
				(anchor circle)
			)
			(primitives
				(gr_poly
					(pts
						(arc
							(start -0.254 0.1778)
							(mid -0.239121 0.213721)
							(end -0.2032 0.2286)
						)
						(arc
							(start 0.2032 0.2286)
							(mid 0.239121 0.213721)
							(end 0.254 0.1778)
						)
						(arc
							(start 0.254 -0.1778)
							(mid 0.239121 -0.213721)
							(end 0.2032 -0.2286)
						)
						(arc
							(start -0.2032 -0.2286)
							(mid -0.239121 -0.213721)
							(end -0.254 -0.1778)
						)
					)
					(width 0)
					(fill yes)
				)
			)
		)
	)
	(footprint ""
		(layer "B.Cu")
		(at 197.485 -33.782 -90)
		(property "Reference" "R152"
			(at 0 0 90)
			(layer "B.SilkS")
			(hide yes)
			(effects
				(font
					(size 1.27 1.27)
				)
				(justify mirror)
			)
		)
		(property "Value" "300R2F-GP"
			(at -1.7907 -1.1176 270)
			(unlocked yes)
			(layer "B.Fab")
			(hide yes)
			(effects
				(font
					(size 1.016 1.016)
					(thickness 0.1524)
				)
				(justify mirror)
			)
		)
		(property "Device Type" "R402H16"
			(at -1.7907 -2.6416 270)
			(unlocked yes)
			(layer "B.Fab")
			(hide yes)
			(effects
				(font
					(size 1.016 1.016)
					(thickness 0.1524)
				)
				(justify mirror)
			)
		)
		(duplicate_pad_numbers_are_jumpers no)
		(fp_rect
			(start 0.381 0.8382)
			(end -0.381 -0.8382)
			(stroke
				(width 0)
				(type default)
			)
			(fill no)
			(layer "B.CrtYd")
		)
		(fp_rect
			(start 0.381 0.8382)
			(end -0.381 -0.8382)
			(stroke
				(width 0)
				(type default)
			)
			(fill no)
			(layer "B.Fab")
		)
		(pad "1" smd custom
			(at 0 -0.4318 90)
			(size 0.127 0.127)
			(layers "B.Cu" "B.Mask" "B.Paste")
			(net "PORT80_R_BIT3")
			(options
				(clearance outline)
				(anchor circle)
			)
			(primitives
				(gr_poly
					(pts
						(arc
							(start -0.2032 0.2794)
							(mid -0.239121 0.264521)
							(end -0.254 0.2286)
						)
						(arc
							(start -0.254 -0.2286)
							(mid -0.239121 -0.264521)
							(end -0.2032 -0.2794)
						)
						(arc
							(start 0.2032 -0.2794)
							(mid 0.239121 -0.264521)
							(end 0.254 -0.2286)
						)
						(arc
							(start 0.254 0.2286)
							(mid 0.239121 0.264521)
							(end 0.2032 0.2794)
						)
					)
					(width 0)
					(fill yes)
				)
			)
		)
		(pad "2" smd custom
			(at 0 0.4318 90)
			(size 0.127 0.127)
			(layers "B.Cu" "B.Mask" "B.Paste")
			(net "P3V3_STBY")
			(options
				(clearance outline)
				(anchor circle)
			)
			(primitives
				(gr_poly
					(pts
						(arc
							(start -0.2032 0.2794)
							(mid -0.239121 0.264521)
							(end -0.254 0.2286)
						)
						(arc
							(start -0.254 -0.2286)
							(mid -0.239121 -0.264521)
							(end -0.2032 -0.2794)
						)
						(arc
							(start 0.2032 -0.2794)
							(mid 0.239121 -0.264521)
							(end 0.254 -0.2286)
						)
						(arc
							(start 0.254 0.2286)
							(mid 0.239121 0.264521)
							(end 0.2032 0.2794)
						)
					)
					(width 0)
					(fill yes)
				)
			)
		)
	)
	(footprint ""
		(layer "B.Cu")
		(at 33.147 -44.45 -90)
		(property "Reference" "PR185"
			(at 0 0 90)
			(layer "B.SilkS")
			(hide yes)
			(effects
				(font
					(size 1.27 1.27)
				)
				(justify mirror)
			)
		)
		(property "Value" "4K75R2F-1-GP"
			(at -1.7907 -1.1176 270)
			(unlocked yes)
			(layer "B.Fab")
			(hide yes)
			(effects
				(font
					(size 1.016 1.016)
					(thickness 0.1524)
				)
				(justify mirror)
			)
		)
		(property "Device Type" "R402H16"
			(at -1.7907 -2.6416 270)
			(unlocked yes)
			(layer "B.Fab")
			(hide yes)
			(effects
				(font
					(size 1.016 1.016)
					(thickness 0.1524)
				)
				(justify mirror)
			)
		)
		(duplicate_pad_numbers_are_jumpers no)
		(fp_rect
			(start 0.381 0.8382)
			(end -0.381 -0.8382)
			(stroke
				(width 0)
				(type default)
			)
			(fill no)
			(layer "B.CrtYd")
		)
		(fp_rect
			(start 0.381 0.8382)
			(end -0.381 -0.8382)
			(stroke
				(width 0)
				(type default)
			)
			(fill no)
			(layer "B.Fab")
		)
		(pad "1" smd custom
			(at 0 -0.4318 90)
			(size 0.127 0.127)
			(layers "B.Cu" "B.Mask" "B.Paste")
			(net "P1V5_STBY_FB")
			(options
				(clearance outline)
				(anchor circle)
			)
			(primitives
				(gr_poly
					(pts
						(arc
							(start -0.2032 0.2794)
							(mid -0.239121 0.264521)
							(end -0.254 0.2286)
						)
						(arc
							(start -0.254 -0.2286)
							(mid -0.239121 -0.264521)
							(end -0.2032 -0.2794)
						)
						(arc
							(start 0.2032 -0.2794)
							(mid 0.239121 -0.264521)
							(end 0.254 -0.2286)
						)
						(arc
							(start 0.254 0.2286)
							(mid 0.239121 0.264521)
							(end 0.2032 0.2794)
						)
					)
					(width 0)
					(fill yes)
				)
			)
		)
		(pad "2" smd custom
			(at 0 0.4318 90)
			(size 0.127 0.127)
			(layers "B.Cu" "B.Mask" "B.Paste")
			(net "GND")
			(options
				(clearance outline)
				(anchor circle)
			)
			(primitives
				(gr_poly
					(pts
						(arc
							(start -0.2032 0.2794)
							(mid -0.239121 0.264521)
							(end -0.254 0.2286)
						)
						(arc
							(start -0.254 -0.2286)
							(mid -0.239121 -0.264521)
							(end -0.2032 -0.2794)
						)
						(arc
							(start 0.2032 -0.2794)
							(mid 0.239121 -0.264521)
							(end 0.254 -0.2286)
						)
						(arc
							(start 0.254 0.2286)
							(mid 0.239121 0.264521)
							(end 0.2032 0.2794)
						)
					)
					(width 0)
					(fill yes)
				)
			)
		)
	)
	(footprint ""
		(layer "B.Cu")
		(at 110.363 -52.197 90)
		(property "Reference" "C126"
			(at 0 0 90)
			(layer "B.SilkS")
			(hide yes)
			(effects
				(font
					(size 1.27 1.27)
				)
				(justify mirror)
			)
		)
		(property "Value" "SC22U6D3V5MX-2GP"
			(at 0.0762 -6.1214 90)
			(unlocked yes)
			(layer "B.Fab")
			(hide yes)
			(effects
				(font
					(size 1.016 1.016)
					(thickness 0.1524)
				)
				(justify mirror)
			)
		)
		(property "Device Type" "C805H58"
			(at 0.0762 -8.1534 90)
			(unlocked yes)
			(layer "B.Fab")
			(hide yes)
			(effects
				(font
					(size 1.016 1.016)
					(thickness 0.1524)
				)
				(justify mirror)
			)
		)
		(duplicate_pad_numbers_are_jumpers no)
		(fp_line
			(start -0.6096 0)
			(end 0.6096 0)
			(stroke
				(width 0.3048)
				(type default)
			)
			(layer "B.SilkS")
		)
		(fp_poly
			(pts
				(xy 0.9017 1.4351) (xy -0.9017 1.4351) (xy -0.9017 -1.4351) (xy 0.9017 -1.4351)
			)
			(stroke
				(width 0)
				(type default)
			)
			(fill no)
			(layer "B.CrtYd")
		)
		(fp_poly
			(pts
				(xy -0.9017 1.4351) (xy -0.9017 -1.4351) (xy 0.9017 -1.4351) (xy 0.9017 1.4351)
			)
			(stroke
				(width 0)
				(type default)
			)
			(fill no)
			(layer "B.Fab")
		)
		(pad "1" smd rect
			(at 0 -0.8382 270)
			(size 1.5494 0.9398)
			(layers "B.Cu" "B.Mask" "B.Paste")
			(net "PV_VDDR")
		)
		(pad "2" smd rect
			(at 0 0.8382 270)
			(size 1.5494 0.9398)
			(layers "B.Cu" "B.Mask" "B.Paste")
			(net "GND")
		)
	)
	(footprint ""
		(layer "B.Cu")
		(at 121.666 -68.7578)
		(property "Reference" "R238"
			(at 0 0 0)
			(layer "B.SilkS")
			(hide yes)
			(effects
				(font
					(size 1.27 1.27)
				)
				(justify mirror)
			)
		)
		(property "Value" "0R2J-2-GP"
			(at -0.064008 -3.993896 0)
			(unlocked yes)
			(layer "B.Fab")
			(hide yes)
			(effects
				(font
					(size 1.016 1.016)
					(thickness 0.1524)
				)
				(justify mirror)
			)
		)
		(property "Device Type" "R402H16"
			(at -0.064008 -5.517896 0)
			(unlocked yes)
			(layer "B.Fab")
			(hide yes)
			(effects
				(font
					(size 1.016 1.016)
					(thickness 0.1524)
				)
				(justify mirror)
			)
		)
		(duplicate_pad_numbers_are_jumpers no)
		(fp_rect
			(start 0.381 0.8382)
			(end -0.381 -0.8382)
			(stroke
				(width 0)
				(type default)
			)
			(fill no)
			(layer "B.CrtYd")
		)
		(fp_rect
			(start 0.381 0.8382)
			(end -0.381 -0.8382)
			(stroke
				(width 0)
				(type default)
			)
			(fill no)
			(layer "B.Fab")
		)
		(pad "1" smd custom
			(at 0 -0.4318 180)
			(size 0.127 0.127)
			(layers "B.Cu" "B.Mask" "B.Paste")
			(net "SMB_M_A0_R_DATA")
			(options
				(clearance outline)
				(anchor circle)
			)
			(primitives
				(gr_poly
					(pts
						(arc
							(start -0.2032 0.2794)
							(mid -0.239121 0.264521)
							(end -0.254 0.2286)
						)
						(arc
							(start -0.254 -0.2286)
							(mid -0.239121 -0.264521)
							(end -0.2032 -0.2794)
						)
						(arc
							(start 0.2032 -0.2794)
							(mid 0.239121 -0.264521)
							(end 0.254 -0.2286)
						)
						(arc
							(start 0.254 0.2286)
							(mid 0.239121 0.264521)
							(end 0.2032 0.2794)
						)
					)
					(width 0)
					(fill yes)
				)
			)
		)
		(pad "2" smd custom
			(at 0 0.4318 180)
			(size 0.127 0.127)
			(layers "B.Cu" "B.Mask" "B.Paste")
			(net "SMB_HOST_LV_DATA")
			(options
				(clearance outline)
				(anchor circle)
			)
			(primitives
				(gr_poly
					(pts
						(arc
							(start -0.2032 0.2794)
							(mid -0.239121 0.264521)
							(end -0.254 0.2286)
						)
						(arc
							(start -0.254 -0.2286)
							(mid -0.239121 -0.264521)
							(end -0.2032 -0.2794)
						)
						(arc
							(start 0.2032 -0.2794)
							(mid 0.239121 -0.264521)
							(end 0.254 -0.2286)
						)
						(arc
							(start 0.254 0.2286)
							(mid 0.239121 0.264521)
							(end 0.2032 0.2794)
						)
					)
					(width 0)
					(fill yes)
				)
			)
		)
	)
	(footprint ""
		(layer "B.Cu")
		(at 91.4146 -38.5826 90)
		(property "Reference" "C183"
			(at 0 0 90)
			(layer "B.SilkS")
			(hide yes)
			(effects
				(font
					(size 1.27 1.27)
				)
				(justify mirror)
			)
		)
		(property "Value" "SCD1U16V2KX-3GP"
			(at -1.1811 -2.7051 90)
			(unlocked yes)
			(layer "B.Fab")
			(hide yes)
			(effects
				(font
					(size 1.016 1.016)
					(thickness 0.1524)
				)
				(justify mirror)
			)
		)
		(property "Device Type" "C402H22"
			(at -1.1811 -4.2291 90)
			(unlocked yes)
			(layer "B.Fab")
			(hide yes)
			(effects
				(font
					(size 1.016 1.016)
					(thickness 0.1524)
				)
				(justify mirror)
			)
		)
		(duplicate_pad_numbers_are_jumpers no)
		(fp_rect
			(start 0.381 0.7366)
			(end -0.381 -0.7366)
			(stroke
				(width 0)
				(type default)
			)
			(fill no)
			(layer "B.CrtYd")
		)
		(fp_rect
			(start 0.381 0.7366)
			(end -0.381 -0.7366)
			(stroke
				(width 0)
				(type default)
			)
			(fill no)
			(layer "B.Fab")
		)
		(pad "1" smd custom
			(at 0 -0.4572 270)
			(size 0.1143 0.1143)
			(layers "B.Cu" "B.Mask" "B.Paste")
			(net "P3V3_RTC")
			(options
				(clearance outline)
				(anchor circle)
			)
			(primitives
				(gr_poly
					(pts
						(arc
							(start -0.254 0.1778)
							(mid -0.239121 0.213721)
							(end -0.2032 0.2286)
						)
						(arc
							(start 0.2032 0.2286)
							(mid 0.239121 0.213721)
							(end 0.254 0.1778)
						)
						(arc
							(start 0.254 -0.1778)
							(mid 0.239121 -0.213721)
							(end 0.2032 -0.2286)
						)
						(arc
							(start -0.2032 -0.2286)
							(mid -0.239121 -0.213721)
							(end -0.254 -0.1778)
						)
					)
					(width 0)
					(fill yes)
				)
			)
		)
		(pad "2" smd custom
			(at 0 0.4572 270)
			(size 0.1143 0.1143)
			(layers "B.Cu" "B.Mask" "B.Paste")
			(net "GND")
			(options
				(clearance outline)
				(anchor circle)
			)
			(primitives
				(gr_poly
					(pts
						(arc
							(start -0.254 0.1778)
							(mid -0.239121 0.213721)
							(end -0.2032 0.2286)
						)
						(arc
							(start 0.2032 0.2286)
							(mid 0.239121 0.213721)
							(end 0.254 0.1778)
						)
						(arc
							(start 0.254 -0.1778)
							(mid 0.239121 -0.213721)
							(end 0.2032 -0.2286)
						)
						(arc
							(start -0.2032 -0.2286)
							(mid -0.239121 -0.213721)
							(end -0.254 -0.1778)
						)
					)
					(width 0)
					(fill yes)
				)
			)
		)
	)
	(footprint ""
		(layer "B.Cu")
		(at 98.933 -38.598602 180)
		(property "Reference" "C185"
			(at 0 0 0)
			(layer "B.SilkS")
			(hide yes)
			(effects
				(font
					(size 1.27 1.27)
				)
				(justify mirror)
			)
		)
		(property "Value" "SC2D2U10V2KX-GP"
			(at -1.1811 -2.7051 180)
			(unlocked yes)
			(layer "B.Fab")
			(hide yes)
			(effects
				(font
					(size 1.016 1.016)
					(thickness 0.1524)
				)
				(justify mirror)
			)
		)
		(property "Device Type" "C402H22"
			(at -1.1811 -4.2291 180)
			(unlocked yes)
			(layer "B.Fab")
			(hide yes)
			(effects
				(font
					(size 1.016 1.016)
					(thickness 0.1524)
				)
				(justify mirror)
			)
		)
		(duplicate_pad_numbers_are_jumpers no)
		(fp_rect
			(start 0.381 0.7366)
			(end -0.381 -0.7366)
			(stroke
				(width 0)
				(type default)
			)
			(fill no)
			(layer "B.CrtYd")
		)
		(fp_rect
			(start 0.381 0.7366)
			(end -0.381 -0.7366)
			(stroke
				(width 0)
				(type default)
			)
			(fill no)
			(layer "B.Fab")
		)
		(pad "1" smd custom
			(at 0 -0.4572)
			(size 0.1143 0.1143)
			(layers "B.Cu" "B.Mask" "B.Paste")
			(net "P1V0")
			(options
				(clearance outline)
				(anchor circle)
			)
			(primitives
				(gr_poly
					(pts
						(arc
							(start -0.254 0.1778)
							(mid -0.239121 0.213721)
							(end -0.2032 0.2286)
						)
						(arc
							(start 0.2032 0.2286)
							(mid 0.239121 0.213721)
							(end 0.254 0.1778)
						)
						(arc
							(start 0.254 -0.1778)
							(mid 0.239121 -0.213721)
							(end 0.2032 -0.2286)
						)
						(arc
							(start -0.2032 -0.2286)
							(mid -0.239121 -0.213721)
							(end -0.254 -0.1778)
						)
					)
					(width 0)
					(fill yes)
				)
			)
		)
		(pad "2" smd custom
			(at 0 0.4572)
			(size 0.1143 0.1143)
			(layers "B.Cu" "B.Mask" "B.Paste")
			(net "GND")
			(options
				(clearance outline)
				(anchor circle)
			)
			(primitives
				(gr_poly
					(pts
						(arc
							(start -0.254 0.1778)
							(mid -0.239121 0.213721)
							(end -0.2032 0.2286)
						)
						(arc
							(start 0.2032 0.2286)
							(mid 0.239121 0.213721)
							(end 0.254 0.1778)
						)
						(arc
							(start 0.254 -0.1778)
							(mid 0.239121 -0.213721)
							(end 0.2032 -0.2286)
						)
						(arc
							(start -0.2032 -0.2286)
							(mid -0.239121 -0.213721)
							(end -0.254 -0.1778)
						)
					)
					(width 0)
					(fill yes)
				)
			)
		)
	)
)
